# S9S_MB_2U (Grand Teton) — schematic netlist excerpt (pin names and nets, part order shuffled) for the footprints in the layout excerpt that follows; sources: Cadence DE-HDL packaged netlist, KiCad conversion of 03242023_DA0F0TMBIJ0_F0T_Motherboard_J_brd_V01_OCP.brd

R4687  Q_RES  4.7K 1% EMPTY  pkg 0402LF  page 251 : A = GND ; B = HSC_TYPE_ADC_A1
PC1369  Q_CAP  0.1UF 25V 10% X7R  pkg 0402  page 290 : A = GND ; B = PVCCIN_CPU1_VREF

(kicad_pcb
	(version 20260206)
	(generator "pcbnew")
	(generator_version "10.0")
	(general
		(thickness 1.6)
		(legacy_teardrops no)
	)
	(paper "A4")
	(title_block
		(title "03242023_DA0F0TMBIJ0_F0T_Motherboard_J_brd_V01_OCP.brd")
		(comment 1 "Grand Teton / footprints 2335-2336 of 6105")
	)
	(layers
		(0 "F.Cu" signal "TOP")
		(4 "In1.Cu" signal "GND")
		(6 "In2.Cu" signal "IN1")
		(8 "In3.Cu" signal "GND1")
		(10 "In4.Cu" signal "IN2")
		(12 "In5.Cu" signal "GND2")
		(14 "In6.Cu" signal "IN3")
		(16 "In7.Cu" signal "GND3")
		(18 "In8.Cu" signal "VCC")
		(20 "In9.Cu" signal "VCC1")
		(22 "In10.Cu" signal "GND4")
		(24 "In11.Cu" signal "IN4")
		(26 "In12.Cu" signal "GND5")
		(28 "In13.Cu" signal "IN5")
		(30 "In14.Cu" signal "GND6")
		(32 "In15.Cu" signal "IN6")
		(34 "In16.Cu" signal "GND7")
		(2 "B.Cu" signal "BOTTOM")
		(9 "F.Adhes" user "F.Adhesive")
		(11 "B.Adhes" user "B.Adhesive")
		(13 "F.Paste" user "Package Geometry/Pastemask Top")
		(15 "B.Paste" user "Package Geometry/Pastemask Bottom")
		(5 "F.SilkS" user "Ref Des/Silkscreen Top")
		(7 "B.SilkS" user "Ref Des/Silkscreen Bottom")
		(1 "F.Mask" user "Board Geometry/Soldermask Top")
		(3 "B.Mask" user "Board Geometry/Soldermask Bottom")
		(17 "Dwgs.User" user "User.Drawings")
		(19 "Cmts.User" user "User.Comments")
		(21 "Eco1.User" user "User.Eco1")
		(23 "Eco2.User" user "User.Eco2")
		(25 "Edge.Cuts" user "Board Geometry/Outline")
		(27 "Margin" user)
		(31 "F.CrtYd" user "Package Geometry/Place Bound Top")
		(29 "B.CrtYd" user "Package Geometry/Place Bound Bottom")
		(35 "F.Fab" user "Ref Des/Assembly Top")
		(33 "B.Fab" user "Ref Des/Assembly Bottom")
	)
	(footprint ""
		(layer "F.Cu")
		(at 294.045894 -415.00552)
		(property "Reference" "R4687"
			(at 0 0 0)
			(layer "F.SilkS")
			(hide yes)
			(effects
				(font
					(size 1.27 1.27)
				)
			)
		)
		(property "Value" ""
			(at 0 0 0)
			(layer "F.Fab")
			(effects
				(font
					(size 1.27 1.27)
				)
			)
		)
		(duplicate_pad_numbers_are_jumpers no)
		(fp_line
			(start -0.7874 -0.4064)
			(end 0.7874 -0.4064)
			(stroke
				(width 0.1524)
				(type default)
			)
			(layer "F.SilkS")
		)
		(fp_line
			(start -0.7874 0.4064)
			(end -0.7874 -0.4064)
			(stroke
				(width 0.1524)
				(type default)
			)
			(layer "F.SilkS")
		)
		(fp_line
			(start 0.7874 -0.4064)
			(end 0.7874 0.4064)
			(stroke
				(width 0.1524)
				(type default)
			)
			(layer "F.SilkS")
		)
		(fp_line
			(start 0.7874 0.4064)
			(end -0.7874 0.4064)
			(stroke
				(width 0.1524)
				(type default)
			)
			(layer "F.SilkS")
		)
		(fp_line
			(start -0.67945 -0.305054)
			(end -0.12065 -0.305054)
			(stroke
				(width 0.1)
				(type default)
			)
			(layer "F.Fab")
		)
		(fp_line
			(start -0.67945 0.3048)
			(end -0.67945 -0.305054)
			(stroke
				(width 0.1)
				(type default)
			)
			(layer "F.Fab")
		)
		(fp_line
			(start -0.12065 -0.305054)
			(end -0.12065 -0.2794)
			(stroke
				(width 0.1)
				(type default)
			)
			(layer "F.Fab")
		)
		(fp_line
			(start -0.12065 -0.2794)
			(end 0.12065 -0.2794)
			(stroke
				(width 0.1)
				(type default)
			)
			(layer "F.Fab")
		)
		(fp_line
			(start -0.12065 0.2794)
			(end -0.12065 0.3048)
			(stroke
				(width 0.1)
				(type default)
			)
			(layer "F.Fab")
		)
		(fp_line
			(start -0.12065 0.3048)
			(end -0.67945 0.3048)
			(stroke
				(width 0.1)
				(type default)
			)
			(layer "F.Fab")
		)
		(fp_line
			(start 0.120396 0.2794)
			(end -0.12065 0.2794)
			(stroke
				(width 0.1)
				(type default)
			)
			(layer "F.Fab")
		)
		(fp_line
			(start 0.120396 0.3048)
			(end 0.120396 0.2794)
			(stroke
				(width 0.1)
				(type default)
			)
			(layer "F.Fab")
		)
		(fp_line
			(start 0.12065 -0.3048)
			(end 0.67945 -0.3048)
			(stroke
				(width 0.1)
				(type default)
			)
			(layer "F.Fab")
		)
		(fp_line
			(start 0.12065 -0.2794)
			(end 0.12065 -0.3048)
			(stroke
				(width 0.1)
				(type default)
			)
			(layer "F.Fab")
		)
		(fp_line
			(start 0.67945 -0.3048)
			(end 0.67945 0.3048)
			(stroke
				(width 0.1)
				(type default)
			)
			(layer "F.Fab")
		)
		(fp_line
			(start 0.67945 0.3048)
			(end 0.120396 0.3048)
			(stroke
				(width 0.1)
				(type default)
			)
			(layer "F.Fab")
		)
		(pad "1" smd circle
			(at -0.40005 0)
			(size 0 0)
			(layers "F.Cu" "F.Mask" "F.Paste")
			(net "GND")
		)
		(pad "2" smd circle
			(at 0.40005 0)
			(size 0 0)
			(layers "F.Cu" "F.Mask" "F.Paste")
			(net "HSC_TYPE_ADC_A1")
		)
	)
	(footprint ""
		(layer "F.Cu")
		(at 178.960272 -358.135936 -90)
		(property "Reference" "PC1369"
			(at 0 0 270)
			(layer "F.SilkS")
			(hide yes)
			(effects
				(font
					(size 1.27 1.27)
				)
			)
		)
		(property "Value" ""
			(at 0 0 270)
			(layer "F.Fab")
			(effects
				(font
					(size 1.27 1.27)
				)
			)
		)
		(duplicate_pad_numbers_are_jumpers no)
		(fp_line
			(start -0.7874 0.4064)
			(end -0.7874 -0.4064)
			(stroke
				(width 0.1524)
				(type default)
			)
			(layer "F.SilkS")
		)
		(fp_line
			(start 0.7874 0.4064)
			(end -0.7874 0.4064)
			(stroke
				(width 0.1524)
				(type default)
			)
			(layer "F.SilkS")
		)
		(fp_line
			(start -0.7874 -0.4064)
			(end 0.7874 -0.4064)
			(stroke
				(width 0.1524)
				(type default)
			)
			(layer "F.SilkS")
		)
		(fp_line
			(start 0.7874 -0.4064)
			(end 0.7874 0.4064)
			(stroke
				(width 0.1524)
				(type default)
			)
			(layer "F.SilkS")
		)
		(fp_line
			(start -0.67945 0.3048)
			(end -0.67945 -0.305054)
			(stroke
				(width 0.1)
				(type default)
			)
			(layer "F.Fab")
		)
		(fp_line
			(start -0.12065 0.3048)
			(end -0.67945 0.3048)
			(stroke
				(width 0.1)
				(type default)
			)
			(layer "F.Fab")
		)
		(fp_line
			(start 0.120396 0.3048)
			(end 0.120396 0.2794)
			(stroke
				(width 0.1)
				(type default)
			)
			(layer "F.Fab")
		)
		(fp_line
			(start 0.67945 0.3048)
			(end 0.120396 0.3048)
			(stroke
				(width 0.1)
				(type default)
			)
			(layer "F.Fab")
		)
		(fp_line
			(start -0.12065 0.2794)
			(end -0.12065 0.3048)
			(stroke
				(width 0.1)
				(type default)
			)
			(layer "F.Fab")
		)
		(fp_line
			(start 0.120396 0.2794)
			(end -0.12065 0.2794)
			(stroke
				(width 0.1)
				(type default)
			)
			(layer "F.Fab")
		)
		(fp_line
			(start -0.12065 -0.2794)
			(end 0.12065 -0.2794)
			(stroke
				(width 0.1)
				(type default)
			)
			(layer "F.Fab")
		)
		(fp_line
			(start 0.12065 -0.2794)
			(end 0.12065 -0.3048)
			(stroke
				(width 0.1)
				(type default)
			)
			(layer "F.Fab")
		)
		(fp_line
			(start 0.12065 -0.3048)
			(end 0.67945 -0.3048)
			(stroke
				(width 0.1)
				(type default)
			)
			(layer "F.Fab")
		)
		(fp_line
			(start 0.67945 -0.3048)
			(end 0.67945 0.3048)
			(stroke
				(width 0.1)
				(type default)
			)
			(layer "F.Fab")
		)
		(fp_line
			(start -0.67945 -0.305054)
			(end -0.12065 -0.305054)
			(stroke
				(width 0.1)
				(type default)
			)
			(layer "F.Fab")
		)
		(fp_line
			(start -0.12065 -0.305054)
			(end -0.12065 -0.2794)
			(stroke
				(width 0.1)
				(type default)
			)
			(layer "F.Fab")
		)
		(pad "1" smd circle
			(at -0.40005 0 270)
			(size 0 0)
			(layers "F.Cu" "F.Mask" "F.Paste")
			(net "GND")
		)
		(pad "2" smd circle
			(at 0.40005 0 270)
			(size 0 0)
			(layers "F.Cu" "F.Mask" "F.Paste")
			(net "PVCCIN_CPU1_VREF")
		)
	)
)
